(kicad_pcb
	(version 20260206)
	(generator "pcbnew")
	(generator_version "10.0")
	(general
		(thickness 1.6)
		(legacy_teardrops no)
	)
	(paper "A4")
	(title_block
		(title "03242023_DA0F0TMBIJ0_F0T_Motherboard_J_brd_V01_OCP.brd")
		(comment 1 "Grand Teton / footprints 873-878 of 6105")
	)
	(layers
		(0 "F.Cu" signal "TOP")
		(4 "In1.Cu" signal "GND")
		(6 "In2.Cu" signal "IN1")
		(8 "In3.Cu" signal "GND1")
		(10 "In4.Cu" signal "IN2")
		(12 "In5.Cu" signal "GND2")
		(14 "In6.Cu" signal "IN3")
		(16 "In7.Cu" signal "GND3")
		(18 "In8.Cu" signal "VCC")
		(20 "In9.Cu" signal "VCC1")
		(22 "In10.Cu" signal "GND4")
		(24 "In11.Cu" signal "IN4")
		(26 "In12.Cu" signal "GND5")
		(28 "In13.Cu" signal "IN5")
		(30 "In14.Cu" signal "GND6")
		(32 "In15.Cu" signal "IN6")
		(34 "In16.Cu" signal "GND7")
		(2 "B.Cu" signal "BOTTOM")
		(9 "F.Adhes" user "F.Adhesive")
		(11 "B.Adhes" user "B.Adhesive")
		(13 "F.Paste" user "Package Geometry/Pastemask Top")
		(15 "B.Paste" user "Package Geometry/Pastemask Bottom")
		(5 "F.SilkS" user "Ref Des/Silkscreen Top")
		(7 "B.SilkS" user "Ref Des/Silkscreen Bottom")
		(1 "F.Mask" user "Board Geometry/Soldermask Top")
		(3 "B.Mask" user "Board Geometry/Soldermask Bottom")
		(17 "Dwgs.User" user "User.Drawings")
		(19 "Cmts.User" user "User.Comments")
		(21 "Eco1.User" user "User.Eco1")
		(23 "Eco2.User" user "User.Eco2")
		(25 "Edge.Cuts" user "Board Geometry/Outline")
		(27 "Margin" user)
		(31 "F.CrtYd" user "Package Geometry/Place Bound Top")
		(29 "B.CrtYd" user "Package Geometry/Place Bound Bottom")
		(35 "F.Fab" user "Ref Des/Assembly Top")
		(33 "B.Fab" user "Ref Des/Assembly Bottom")
	)
	(footprint ""
		(layer "F.Cu")
		(at 309.522622 -42.916348 180)
		(property "Reference" "R381"
			(at 0 0 180)
			(layer "F.SilkS")
			(hide yes)
			(effects
				(font
					(size 1.27 1.27)
				)
			)
		)
		(property "Value" ""
			(at 0 0 180)
			(layer "F.Fab")
			(effects
				(font
					(size 1.27 1.27)
				)
			)
		)
		(duplicate_pad_numbers_are_jumpers no)
		(fp_line
			(start 0.7874 0.4064)
			(end -0.7874 0.4064)
			(stroke
				(width 0.1524)
				(type default)
			)
			(layer "F.SilkS")
		)
		(fp_line
			(start 0.7874 -0.4064)
			(end 0.7874 0.4064)
			(stroke
				(width 0.1524)
				(type default)
			)
			(layer "F.SilkS")
		)
		(fp_line
			(start -0.7874 0.4064)
			(end -0.7874 -0.4064)
			(stroke
				(width 0.1524)
				(type default)
			)
			(layer "F.SilkS")
		)
		(fp_line
			(start -0.7874 -0.4064)
			(end 0.7874 -0.4064)
			(stroke
				(width 0.1524)
				(type default)
			)
			(layer "F.SilkS")
		)
		(fp_line
			(start 0.67945 0.3048)
			(end 0.120396 0.3048)
			(stroke
				(width 0.1)
				(type default)
			)
			(layer "F.Fab")
		)
		(fp_line
			(start 0.67945 -0.3048)
			(end 0.67945 0.3048)
			(stroke
				(width 0.1)
				(type default)
			)
			(layer "F.Fab")
		)
		(fp_line
			(start 0.12065 -0.2794)
			(end 0.12065 -0.3048)
			(stroke
				(width 0.1)
				(type default)
			)
			(layer "F.Fab")
		)
		(fp_line
			(start 0.12065 -0.3048)
			(end 0.67945 -0.3048)
			(stroke
				(width 0.1)
				(type default)
			)
			(layer "F.Fab")
		)
		(fp_line
			(start 0.120396 0.3048)
			(end 0.120396 0.2794)
			(stroke
				(width 0.1)
				(type default)
			)
			(layer "F.Fab")
		)
		(fp_line
			(start 0.120396 0.2794)
			(end -0.12065 0.2794)
			(stroke
				(width 0.1)
				(type default)
			)
			(layer "F.Fab")
		)
		(fp_line
			(start -0.12065 0.3048)
			(end -0.67945 0.3048)
			(stroke
				(width 0.1)
				(type default)
			)
			(layer "F.Fab")
		)
		(fp_line
			(start -0.12065 0.2794)
			(end -0.12065 0.3048)
			(stroke
				(width 0.1)
				(type default)
			)
			(layer "F.Fab")
		)
		(fp_line
			(start -0.12065 -0.2794)
			(end 0.12065 -0.2794)
			(stroke
				(width 0.1)
				(type default)
			)
			(layer "F.Fab")
		)
		(fp_line
			(start -0.12065 -0.305054)
			(end -0.12065 -0.2794)
			(stroke
				(width 0.1)
				(type default)
			)
			(layer "F.Fab")
		)
		(fp_line
			(start -0.67945 0.3048)
			(end -0.67945 -0.305054)
			(stroke
				(width 0.1)
				(type default)
			)
			(layer "F.Fab")
		)
		(fp_line
			(start -0.67945 -0.305054)
			(end -0.12065 -0.305054)
			(stroke
				(width 0.1)
				(type default)
			)
			(layer "F.Fab")
		)
		(pad "1" smd circle
			(at -0.40005 0 180)
			(size 0 0)
			(layers "F.Cu" "F.Mask" "F.Paste")
			(net "FM_FLASH_SECURITY_STRAP")
		)
		(pad "2" smd circle
			(at 0.40005 0 180)
			(size 0 0)
			(layers "F.Cu" "F.Mask" "F.Paste")
			(net "GND")
		)
	)
	(footprint ""
		(layer "F.Cu")
		(at 64.793876 -79.078836)
		(property "Reference" "D76"
			(at -34.444686 34.341308 90)
			(unlocked yes)
			(layer "F.SilkS")
			(effects
				(font
					(size 0.635 0.4064)
					(thickness 0.1524)
				)
				(justify left)
			)
		)
		(property "Value" ""
			(at 0 0 0)
			(layer "F.Fab")
			(effects
				(font
					(size 1.27 1.27)
				)
			)
		)
		(duplicate_pad_numbers_are_jumpers no)
		(fp_line
			(start -0.90678 0.4826)
			(end -0.90678 -0.4699)
			(stroke
				(width 0.1524)
				(type default)
			)
			(layer "F.SilkS")
		)
		(fp_line
			(start -0.89408 -0.4826)
			(end 0.90678 -0.4826)
			(stroke
				(width 0.1524)
				(type default)
			)
			(layer "F.SilkS")
		)
		(fp_line
			(start -0.79248 -0.4826)
			(end 1.03378 -0.4826)
			(stroke
				(width 0.1524)
				(type default)
			)
			(layer "F.SilkS")
		)
		(fp_line
			(start -0.64008 -0.4826)
			(end 1.16078 -0.4826)
			(stroke
				(width 0.1524)
				(type default)
			)
			(layer "F.SilkS")
		)
		(fp_line
			(start 0.90678 -0.4826)
			(end 0.90678 0.4826)
			(stroke
				(width 0.1524)
				(type default)
			)
			(layer "F.SilkS")
		)
		(fp_line
			(start 0.90678 0.4826)
			(end -0.90678 0.4826)
			(stroke
				(width 0.1524)
				(type default)
			)
			(layer "F.SilkS")
		)
		(fp_line
			(start 1.03378 -0.4826)
			(end 1.03378 0.4826)
			(stroke
				(width 0.1524)
				(type default)
			)
			(layer "F.SilkS")
		)
		(fp_line
			(start 1.03378 0.4826)
			(end -0.79248 0.4826)
			(stroke
				(width 0.1524)
				(type default)
			)
			(layer "F.SilkS")
		)
		(fp_line
			(start 1.16078 -0.4826)
			(end 1.16078 0.4826)
			(stroke
				(width 0.1524)
				(type default)
			)
			(layer "F.SilkS")
		)
		(fp_line
			(start 1.16078 0.4826)
			(end -0.64008 0.4826)
			(stroke
				(width 0.1524)
				(type default)
			)
			(layer "F.SilkS")
		)
		(fp_line
			(start -0.499872 -0.249936)
			(end 0.499872 -0.249936)
			(stroke
				(width 0.1)
				(type default)
			)
			(layer "F.Fab")
		)
		(fp_line
			(start -0.499872 0.249936)
			(end -0.499872 -0.249936)
			(stroke
				(width 0.1)
				(type default)
			)
			(layer "F.Fab")
		)
		(fp_line
			(start 0.499872 -0.249936)
			(end 0.499872 0.249936)
			(stroke
				(width 0.1)
				(type default)
			)
			(layer "F.Fab")
		)
		(fp_line
			(start 0.499872 0.249936)
			(end -0.499872 0.249936)
			(stroke
				(width 0.1)
				(type default)
			)
			(layer "F.Fab")
		)
		(pad "A" smd rect
			(at -0.47498 0)
			(size 0.6096 0.7112)
			(layers "F.Cu" "F.Mask" "F.Paste")
			(net "LED_PWRGD_PVCCFA_EHV_FIVRA_CPU0")
		)
		(pad "C" smd rect
			(at 0.47498 0)
			(size 0.6096 0.7112)
			(layers "F.Cu" "F.Mask" "F.Paste")
			(net "LED_PWRGD_PVCCFA_EHV_FIVRA_CP_1")
		)
	)
	(footprint ""
		(layer "F.Cu")
		(at 506.598428 -153.16708 -90)
		(property "Reference" "X9"
			(at -1.373124 2.750058 90)
			(unlocked yes)
			(layer "F.SilkS")
			(effects
				(font
					(size 0.7874 0.5842)
					(thickness 0.1524)
				)
				(justify left)
			)
		)
		(property "Value" ""
			(at 0 0 270)
			(layer "F.Fab")
			(effects
				(font
					(size 1.27 1.27)
				)
			)
		)
		(property "Device Type" "TP_TDR_4P_FTS_MPKT4_H025P0200_I"
			(at 1.30175 1.27 0)
			(unlocked yes)
			(layer "F.Fab")
			(hide yes)
			(effects
				(font
					(size 0.635 0.4064)
					(thickness 0.1524)
				)
			)
		)
		(property "User Part Number" "TP15"
			(at 1.30175 1.27 0)
			(unlocked yes)
			(layer "Cmts.User")
			(hide yes)
			(effects
				(font
					(size 0.635 0.4064)
					(thickness 0.1524)
				)
			)
		)
		(duplicate_pad_numbers_are_jumpers no)
		(fp_line
			(start 0 3.81)
			(end 2.54 3.81)
			(stroke
				(width 0.1524)
				(type default)
			)
			(layer "F.SilkS")
		)
		(fp_line
			(start 2.54 3.81)
			(end 2.54 3.6703)
			(stroke
				(width 0.1524)
				(type default)
			)
			(layer "F.SilkS")
		)
		(fp_line
			(start 0 3.175)
			(end 0 3.81)
			(stroke
				(width 0.1524)
				(type default)
			)
			(layer "F.SilkS")
		)
		(fp_line
			(start 2.54 1.4097)
			(end 2.54 1.1303)
			(stroke
				(width 0.1524)
				(type default)
			)
			(layer "F.SilkS")
		)
		(fp_line
			(start 0 0.635)
			(end 0 1.905)
			(stroke
				(width 0.1524)
				(type default)
			)
			(layer "F.SilkS")
		)
		(fp_line
			(start 2.54 -1.1303)
			(end 2.54 -1.27)
			(stroke
				(width 0.1524)
				(type default)
			)
			(layer "F.SilkS")
		)
		(fp_line
			(start 0 -1.27)
			(end 0 -0.635)
			(stroke
				(width 0.1524)
				(type default)
			)
			(layer "F.SilkS")
		)
		(fp_line
			(start 2.54 -1.27)
			(end 0 -1.27)
			(stroke
				(width 0.1524)
				(type default)
			)
			(layer "F.SilkS")
		)
		(fp_poly
			(pts
				(xy -1.244346 0) (xy -2.768346 0.762) (xy -2.768346 -0.762)
			)
			(stroke
				(width 0)
				(type default)
			)
			(fill yes)
			(layer "F.SilkS")
		)
		(fp_line
			(start 0 3.81)
			(end 2.54 3.81)
			(stroke
				(width 0.1)
				(type default)
			)
			(layer "F.Fab")
		)
		(fp_line
			(start 2.54 3.81)
			(end 2.54 -1.27)
			(stroke
				(width 0.1)
				(type default)
			)
			(layer "F.Fab")
		)
		(fp_line
			(start 0 -1.27)
			(end 0 3.81)
			(stroke
				(width 0.1)
				(type default)
			)
			(layer "F.Fab")
		)
		(fp_line
			(start 2.54 -1.27)
			(end 0 -1.27)
			(stroke
				(width 0.1)
				(type default)
			)
			(layer "F.Fab")
		)
		(fp_poly
			(pts
				(xy -0.761746 0) (xy -2.285746 -0.762) (xy -2.285746 0.762)
			)
			(stroke
				(width 0)
				(type default)
			)
			(fill yes)
			(layer "F.Fab")
		)
		(pad "1" thru_hole circle
			(at 0 0 270)
			(size 1.0033 1.0033)
			(drill 0.249936)
			(layers "*.Cu" "*.Mask")
			(remove_unused_layers no)
			(net "TDR_DIFF_85_IN2_DN")
			(clearance 0.10795)
			(thermal_gap 0.10795)
			(padstack
				(mode front_inner_back)
				(layer "Inner"
					(shape circle)
					(size 0.8001 0.8001)
					(clearance 0.1524)
				)
				(layer "B.Cu"
					(shape circle)
					(size 1.0033 1.0033)
					(clearance 0.10795)
				)
			)
		)
		(pad "2" thru_hole circle
			(at 2.54 0 270)
			(size 1.9939 1.9939)
			(drill 0.249936)
			(layers "*.Cu" "*.Mask")
			(remove_unused_layers no)
			(net "T1_GND")
			(clearance 0.10795)
			(thermal_gap 0.10795)
			(padstack
				(mode front_inner_back)
				(layer "Inner"
					(shape circle)
					(size 0.8001 0.8001)
					(clearance 0.1524)
				)
				(layer "B.Cu"
					(shape circle)
					(size 1.9939 1.9939)
					(clearance 0.10795)
				)
			)
		)
		(pad "3" thru_hole circle
			(at 2.54 2.54 270)
			(size 1.9939 1.9939)
			(drill 0.249936)
			(layers "*.Cu" "*.Mask")
			(remove_unused_layers no)
			(net "T1_GND")
			(clearance 0.10795)
			(thermal_gap 0.10795)
			(padstack
				(mode front_inner_back)
				(layer "Inner"
					(shape circle)
					(size 0.8001 0.8001)
					(clearance 0.1524)
				)
				(layer "B.Cu"
					(shape circle)
					(size 1.9939 1.9939)
					(clearance 0.10795)
				)
			)
		)
		(pad "4" thru_hole circle
			(at 0 2.54 270)
			(size 1.0033 1.0033)
			(drill 0.249936)
			(layers "*.Cu" "*.Mask")
			(remove_unused_layers no)
			(net "TDR_DIFF_85_IN2_DP")
			(clearance 0.10795)
			(thermal_gap 0.10795)
			(padstack
				(mode front_inner_back)
				(layer "Inner"
					(shape circle)
					(size 0.8001 0.8001)
					(clearance 0.1524)
				)
				(layer "B.Cu"
					(shape circle)
					(size 1.0033 1.0033)
					(clearance 0.10795)
				)
			)
		)
	)
	(footprint ""
		(layer "F.Cu")
		(at 258.37388 -50.565304)
		(property "Reference" "PR3944"
			(at 0 0 0)
			(layer "F.SilkS")
			(hide yes)
			(effects
				(font
					(size 1.27 1.27)
				)
			)
		)
		(property "Value" ""
			(at 0 0 0)
			(layer "F.Fab")
			(effects
				(font
					(size 1.27 1.27)
				)
			)
		)
		(duplicate_pad_numbers_are_jumpers no)
		(fp_line
			(start -0.7874 -0.4064)
			(end 0.7874 -0.4064)
			(stroke
				(width 0.1524)
				(type default)
			)
			(layer "F.SilkS")
		)
		(fp_line
			(start -0.7874 0.4064)
			(end -0.7874 -0.4064)
			(stroke
				(width 0.1524)
				(type default)
			)
			(layer "F.SilkS")
		)
		(fp_line
			(start 0.7874 -0.4064)
			(end 0.7874 0.4064)
			(stroke
				(width 0.1524)
				(type default)
			)
			(layer "F.SilkS")
		)
		(fp_line
			(start 0.7874 0.4064)
			(end -0.7874 0.4064)
			(stroke
				(width 0.1524)
				(type default)
			)
			(layer "F.SilkS")
		)
		(fp_line
			(start -0.67945 -0.305054)
			(end -0.12065 -0.305054)
			(stroke
				(width 0.1)
				(type default)
			)
			(layer "F.Fab")
		)
		(fp_line
			(start -0.67945 0.3048)
			(end -0.67945 -0.305054)
			(stroke
				(width 0.1)
				(type default)
			)
			(layer "F.Fab")
		)
		(fp_line
			(start -0.12065 -0.305054)
			(end -0.12065 -0.2794)
			(stroke
				(width 0.1)
				(type default)
			)
			(layer "F.Fab")
		)
		(fp_line
			(start -0.12065 -0.2794)
			(end 0.12065 -0.2794)
			(stroke
				(width 0.1)
				(type default)
			)
			(layer "F.Fab")
		)
		(fp_line
			(start -0.12065 0.2794)
			(end -0.12065 0.3048)
			(stroke
				(width 0.1)
				(type default)
			)
			(layer "F.Fab")
		)
		(fp_line
			(start -0.12065 0.3048)
			(end -0.67945 0.3048)
			(stroke
				(width 0.1)
				(type default)
			)
			(layer "F.Fab")
		)
		(fp_line
			(start 0.120396 0.2794)
			(end -0.12065 0.2794)
			(stroke
				(width 0.1)
				(type default)
			)
			(layer "F.Fab")
		)
		(fp_line
			(start 0.120396 0.3048)
			(end 0.120396 0.2794)
			(stroke
				(width 0.1)
				(type default)
			)
			(layer "F.Fab")
		)
		(fp_line
			(start 0.12065 -0.3048)
			(end 0.67945 -0.3048)
			(stroke
				(width 0.1)
				(type default)
			)
			(layer "F.Fab")
		)
		(fp_line
			(start 0.12065 -0.2794)
			(end 0.12065 -0.3048)
			(stroke
				(width 0.1)
				(type default)
			)
			(layer "F.Fab")
		)
		(fp_line
			(start 0.67945 -0.3048)
			(end 0.67945 0.3048)
			(stroke
				(width 0.1)
				(type default)
			)
			(layer "F.Fab")
		)
		(fp_line
			(start 0.67945 0.3048)
			(end 0.120396 0.3048)
			(stroke
				(width 0.1)
				(type default)
			)
			(layer "F.Fab")
		)
		(pad "1" smd circle
			(at -0.40005 0)
			(size 0 0)
			(layers "F.Cu" "F.Mask" "F.Paste")
			(net "P12V_E1S_ISET_0")
		)
		(pad "2" smd circle
			(at 0.40005 0)
			(size 0 0)
			(layers "F.Cu" "F.Mask" "F.Paste")
			(net "GND")
		)
	)
	(footprint ""
		(layer "F.Cu")
		(at 224.2312 -51.0921 180)
		(property "Reference" "R4084"
			(at 0 0 180)
			(layer "F.SilkS")
			(hide yes)
			(effects
				(font
					(size 1.27 1.27)
				)
			)
		)
		(property "Value" ""
			(at 0 0 180)
			(layer "F.Fab")
			(effects
				(font
					(size 1.27 1.27)
				)
			)
		)
		(duplicate_pad_numbers_are_jumpers no)
		(fp_line
			(start 0.7874 0.4064)
			(end -0.7874 0.4064)
			(stroke
				(width 0.1524)
				(type default)
			)
			(layer "F.SilkS")
		)
		(fp_line
			(start 0.7874 -0.4064)
			(end 0.7874 0.4064)
			(stroke
				(width 0.1524)
				(type default)
			)
			(layer "F.SilkS")
		)
		(fp_line
			(start -0.7874 0.4064)
			(end -0.7874 -0.4064)
			(stroke
				(width 0.1524)
				(type default)
			)
			(layer "F.SilkS")
		)
		(fp_line
			(start -0.7874 -0.4064)
			(end 0.7874 -0.4064)
			(stroke
				(width 0.1524)
				(type default)
			)
			(layer "F.SilkS")
		)
		(fp_line
			(start 0.67945 0.3048)
			(end 0.120396 0.3048)
			(stroke
				(width 0.1)
				(type default)
			)
			(layer "F.Fab")
		)
		(fp_line
			(start 0.67945 -0.3048)
			(end 0.67945 0.3048)
			(stroke
				(width 0.1)
				(type default)
			)
			(layer "F.Fab")
		)
		(fp_line
			(start 0.12065 -0.2794)
			(end 0.12065 -0.3048)
			(stroke
				(width 0.1)
				(type default)
			)
			(layer "F.Fab")
		)
		(fp_line
			(start 0.12065 -0.3048)
			(end 0.67945 -0.3048)
			(stroke
				(width 0.1)
				(type default)
			)
			(layer "F.Fab")
		)
		(fp_line
			(start 0.120396 0.3048)
			(end 0.120396 0.2794)
			(stroke
				(width 0.1)
				(type default)
			)
			(layer "F.Fab")
		)
		(fp_line
			(start 0.120396 0.2794)
			(end -0.12065 0.2794)
			(stroke
				(width 0.1)
				(type default)
			)
			(layer "F.Fab")
		)
		(fp_line
			(start -0.12065 0.3048)
			(end -0.67945 0.3048)
			(stroke
				(width 0.1)
				(type default)
			)
			(layer "F.Fab")
		)
		(fp_line
			(start -0.12065 0.2794)
			(end -0.12065 0.3048)
			(stroke
				(width 0.1)
				(type default)
			)
			(layer "F.Fab")
		)
		(fp_line
			(start -0.12065 -0.2794)
			(end 0.12065 -0.2794)
			(stroke
				(width 0.1)
				(type default)
			)
			(layer "F.Fab")
		)
		(fp_line
			(start -0.12065 -0.305054)
			(end -0.12065 -0.2794)
			(stroke
				(width 0.1)
				(type default)
			)
			(layer "F.Fab")
		)
		(fp_line
			(start -0.67945 0.3048)
			(end -0.67945 -0.305054)
			(stroke
				(width 0.1)
				(type default)
			)
			(layer "F.Fab")
		)
		(fp_line
			(start -0.67945 -0.305054)
			(end -0.12065 -0.305054)
			(stroke
				(width 0.1)
				(type default)
			)
			(layer "F.Fab")
		)
		(pad "1" smd circle
			(at -0.40005 0 180)
			(size 0 0)
			(layers "F.Cu" "F.Mask" "F.Paste")
			(net "E1S_0_PRSNT_N")
		)
		(pad "2" smd circle
			(at 0.40005 0 180)
			(size 0 0)
			(layers "F.Cu" "F.Mask" "F.Paste")
			(net "E1S_0_CLKREQ_N")
		)
	)
	(footprint ""
		(layer "F.Cu")
		(at 341.627968 -402.371052 -90)
		(property "Reference" "C1555"
			(at 0 0 270)
			(layer "F.SilkS")
			(hide yes)
			(effects
				(font
					(size 1.27 1.27)
				)
			)
		)
		(property "Value" ""
			(at 0 0 270)
			(layer "F.Fab")
			(effects
				(font
					(size 1.27 1.27)
				)
			)
		)
		(duplicate_pad_numbers_are_jumpers no)
		(fp_line
			(start -0.299974 0.150114)
			(end -0.299974 -0.150114)
			(stroke
				(width 0.1)
				(type default)
			)
			(layer "F.Fab")
		)
		(fp_line
			(start 0.299974 0.150114)
			(end -0.299974 0.150114)
			(stroke
				(width 0.1)
				(type default)
			)
			(layer "F.Fab")
		)
		(fp_line
			(start -0.299974 -0.150114)
			(end 0.299974 -0.150114)
			(stroke
				(width 0.1)
				(type default)
			)
			(layer "F.Fab")
		)
		(fp_line
			(start 0.299974 -0.150114)
			(end 0.299974 0.150114)
			(stroke
				(width 0.1)
				(type default)
			)
			(layer "F.Fab")
		)
		(pad "1" smd rect
			(at -0.2667 0 270)
			(size 0.3048 0.381)
			(layers "F.Cu" "F.Mask" "F.Paste")
			(net "P5E_CPU0_PE4_TX_C_DP<12>")
		)
		(pad "2" smd rect
			(at 0.2667 0 270)
			(size 0.3048 0.381)
			(layers "F.Cu" "F.Mask" "F.Paste")
			(net "P5E_CPU0_PE4_TX_DP<12>")
		)
	)
)
